# TIMECARD (Time Appliance Project (Time Card)) — schematic netlist excerpt (pin names and nets, part order shuffled) for the footprints in the layout excerpt that follows; sources: Cadence DE-HDL packaged netlist, KiCad conversion of R4006-B0001-02_R01.brd

C99  CAPACITOR  4.7UF 6.3V 20%  pkg SMC_0402R_H026  page 24 : \1\ = XP3R3V_VPHY ; \2\ = SG
R205  RESISTOR  33OHM 1%  pkg SMC_0402R_H016  page 10 : \1\ = UNNAMED_127_MT25QL128ABA1ESES_3 ; \2\ = FLASH_DQ2

(kicad_pcb
	(version 20260206)
	(generator "pcbnew")
	(generator_version "10.0")
	(general
		(thickness 1.6)
		(legacy_teardrops no)
	)
	(paper "A4")
	(title_block
		(title "timecard-production-celestica-r4006 — R4006-B0001-02_R01.brd")
		(comment 1 "Time Appliance Project (Time Card) / footprints 752-753 of 1113")
	)
	(layers
		(0 "F.Cu" signal "TOP")
		(4 "In1.Cu" signal "L02_GND1")
		(6 "In2.Cu" signal "L03_SIG1")
		(8 "In3.Cu" signal "L04_GND2")
		(10 "In4.Cu" signal "L05_VCC1")
		(12 "In5.Cu" signal "L06_VCC2")
		(14 "In6.Cu" signal "L07_GND3")
		(16 "In7.Cu" signal "L08_SIG2")
		(18 "In8.Cu" signal "L09_GND4")
		(2 "B.Cu" signal "BOTTOM")
		(9 "F.Adhes" user "F.Adhesive")
		(11 "B.Adhes" user "B.Adhesive")
		(13 "F.Paste" user "Package Geometry/Pastemask Top")
		(15 "B.Paste" user "Package Geometry/Pastemask Bottom")
		(5 "F.SilkS" user "Ref Des/Silkscreen Top")
		(7 "B.SilkS" user "Ref Des/Silkscreen Bottom")
		(1 "F.Mask" user "Board Geometry/Soldermask Top")
		(3 "B.Mask" user "Board Geometry/Soldermask Bottom")
		(17 "Dwgs.User" user "User.Drawings")
		(19 "Cmts.User" user "User.Comments")
		(21 "Eco1.User" user "User.Eco1")
		(23 "Eco2.User" user "User.Eco2")
		(25 "Edge.Cuts" user "Board Geometry/Outline")
		(27 "Margin" user)
		(31 "F.CrtYd" user "Package Geometry/Place Bound Top")
		(29 "B.CrtYd" user "Package Geometry/Place Bound Bottom")
		(35 "F.Fab" user "Ref Des/Assembly Top")
		(33 "B.Fab" user "Ref Des/Assembly Bottom")
	)
	(footprint ""
		(layer "B.Cu")
		(at 30.988 -91.059 -90)
		(property "Reference" "C99"
			(at -2.794 -0.21463 270)
			(unlocked yes)
			(layer "B.SilkS")
			(effects
				(font
					(size 0.7874 0.5842)
					(thickness 0.1524)
				)
				(justify mirror)
			)
		)
		(property "Value" "VAL*"
			(at -0.02032 2.13233 270)
			(unlocked yes)
			(layer "B.Fab")
			(hide yes)
			(effects
				(font
					(size 0.7874 0.5842)
					(thickness 0.1524)
				)
				(justify mirror)
			)
		)
		(property "Tolerance" "TOL*"
			(at -0.044704 3.05435 270)
			(unlocked yes)
			(layer "Cmts.User")
			(hide yes)
			(effects
				(font
					(size 0.7874 0.5842)
					(thickness 0.1524)
				)
				(justify mirror)
			)
		)
		(property "User Part Number" "PARTNUM*"
			(at -0.02032 4.024884 270)
			(unlocked yes)
			(layer "Cmts.User")
			(hide yes)
			(effects
				(font
					(size 0.7874 0.5842)
					(thickness 0.1524)
				)
				(justify mirror)
			)
		)
		(property "Device Type" "CAPACITOR-G105-0F475-BM,4.7UF,A"
			(at -0.008382 1.210564 270)
			(unlocked yes)
			(layer "B.Fab")
			(hide yes)
			(effects
				(font
					(size 0.7874 0.5842)
					(thickness 0.1524)
				)
				(justify mirror)
			)
		)
		(duplicate_pad_numbers_are_jumpers no)
		(fp_line
			(start -1.143 0.5588)
			(end -1.143 -0.5588)
			(stroke
				(width 0.1)
				(type default)
			)
			(layer "B.SilkS")
		)
		(fp_line
			(start 1.143 0.5588)
			(end -1.143 0.5588)
			(stroke
				(width 0.1)
				(type default)
			)
			(layer "B.SilkS")
		)
		(fp_line
			(start -1.143 -0.5588)
			(end 1.143 -0.5588)
			(stroke
				(width 0.1)
				(type default)
			)
			(layer "B.SilkS")
		)
		(fp_line
			(start 1.143 -0.5588)
			(end 1.143 0.5588)
			(stroke
				(width 0.1)
				(type default)
			)
			(layer "B.SilkS")
		)
		(fp_poly
			(pts
				(xy 1.143 0.5588) (xy -1.143 0.5588) (xy -1.143 -0.5588) (xy 1.143 -0.5588)
			)
			(stroke
				(width 0)
				(type default)
			)
			(fill no)
			(layer "B.CrtYd")
		)
		(fp_line
			(start -0.508 0.3048)
			(end -0.508 -0.3048)
			(stroke
				(width 0.1)
				(type default)
			)
			(layer "B.Fab")
		)
		(fp_line
			(start 0.508 0.3048)
			(end -0.508 0.3048)
			(stroke
				(width 0.1)
				(type default)
			)
			(layer "B.Fab")
		)
		(fp_line
			(start -0.508 -0.3048)
			(end 0.508 -0.3048)
			(stroke
				(width 0.1)
				(type default)
			)
			(layer "B.Fab")
		)
		(fp_line
			(start 0.508 -0.3048)
			(end 0.508 0.3048)
			(stroke
				(width 0.1)
				(type default)
			)
			(layer "B.Fab")
		)
		(pad "1" smd rect
			(at 0.5334 0 90)
			(size 0.7112 0.6096)
			(layers "B.Cu" "B.Mask" "B.Paste")
			(net "XP3R3V_VPHY")
		)
		(pad "2" smd rect
			(at -0.5334 0 90)
			(size 0.7112 0.6096)
			(layers "B.Cu" "B.Mask" "B.Paste")
			(net "SG")
		)
		(zone
			(layer "B.Cu")
			(hatch none 0.5)
			(connect_pads
				(clearance 0)
			)
			(min_thickness 0.25)
			(keepout
				(tracks allowed)
				(vias not_allowed)
				(pads allowed)
				(copperpour not_allowed)
				(footprints allowed)
			)
			(placement
				(enabled no)
				(sheetname "")
			)
			(fill
				(thermal_gap 0.5)
				(thermal_bridge_width 0.5)
				(island_removal_mode 0)
			)
			(polygon
				(pts
					(xy 30.6832 -90.9828) (xy 31.2928 -90.9828) (xy 31.2928 -91.1352) (xy 30.6832 -91.1352)
				)
			)
		)
		(zone
			(layer "B.Cu")
			(hatch none 0.5)
			(connect_pads
				(clearance 0)
			)
			(min_thickness 0.25)
			(keepout
				(tracks not_allowed)
				(vias allowed)
				(pads allowed)
				(copperpour not_allowed)
				(footprints allowed)
			)
			(placement
				(enabled no)
				(sheetname "")
			)
			(fill
				(thermal_gap 0.5)
				(thermal_bridge_width 0.5)
				(island_removal_mode 0)
			)
			(polygon
				(pts
					(xy 30.6832 -90.9828) (xy 31.2928 -90.9828) (xy 31.2928 -91.1352) (xy 30.6832 -91.1352)
				)
			)
		)
	)
	(footprint ""
		(layer "B.Cu")
		(at 95.631 -86.741)
		(property "Reference" "R205"
			(at -0.254 -5.54863 0)
			(unlocked yes)
			(layer "B.SilkS")
			(effects
				(font
					(size 0.7874 0.5842)
					(thickness 0.1524)
				)
				(justify mirror)
			)
		)
		(property "Value" "VAL*"
			(at -0.02032 2.13233 0)
			(unlocked yes)
			(layer "B.Fab")
			(hide yes)
			(effects
				(font
					(size 0.7874 0.5842)
					(thickness 0.1524)
				)
				(justify mirror)
			)
		)
		(property "Tolerance" "TOL*"
			(at -0.044704 3.05435 0)
			(unlocked yes)
			(layer "Cmts.User")
			(hide yes)
			(effects
				(font
					(size 0.7874 0.5842)
					(thickness 0.1524)
				)
				(justify mirror)
			)
		)
		(property "User Part Number" "PARTNUM*"
			(at -0.02032 4.024884 0)
			(unlocked yes)
			(layer "Cmts.User")
			(hide yes)
			(effects
				(font
					(size 0.7874 0.5842)
					(thickness 0.1524)
				)
				(justify mirror)
			)
		)
		(property "Device Type" "RESISTOR-G155-133R0-01,33OHM,1%"
			(at -0.008382 1.210564 0)
			(unlocked yes)
			(layer "B.Fab")
			(hide yes)
			(effects
				(font
					(size 0.7874 0.5842)
					(thickness 0.1524)
				)
				(justify mirror)
			)
		)
		(duplicate_pad_numbers_are_jumpers no)
		(fp_line
			(start -1.143 -0.5588)
			(end 1.143 -0.5588)
			(stroke
				(width 0.1)
				(type default)
			)
			(layer "B.SilkS")
		)
		(fp_line
			(start -1.143 0.5588)
			(end -1.143 -0.5588)
			(stroke
				(width 0.1)
				(type default)
			)
			(layer "B.SilkS")
		)
		(fp_line
			(start 1.143 -0.5588)
			(end 1.143 0.5588)
			(stroke
				(width 0.1)
				(type default)
			)
			(layer "B.SilkS")
		)
		(fp_line
			(start 1.143 0.5588)
			(end -1.143 0.5588)
			(stroke
				(width 0.1)
				(type default)
			)
			(layer "B.SilkS")
		)
		(fp_rect
			(start -1.143 0.5588)
			(end 1.143 -0.5588)
			(stroke
				(width 0)
				(type default)
			)
			(fill no)
			(layer "B.CrtYd")
		)
		(fp_line
			(start -0.508 -0.3048)
			(end 0.508 -0.3048)
			(stroke
				(width 0.1)
				(type default)
			)
			(layer "B.Fab")
		)
		(fp_line
			(start -0.508 0.3048)
			(end -0.508 -0.3048)
			(stroke
				(width 0.1)
				(type default)
			)
			(layer "B.Fab")
		)
		(fp_line
			(start 0.508 -0.3048)
			(end 0.508 0.3048)
			(stroke
				(width 0.1)
				(type default)
			)
			(layer "B.Fab")
		)
		(fp_line
			(start 0.508 0.3048)
			(end -0.508 0.3048)
			(stroke
				(width 0.1)
				(type default)
			)
			(layer "B.Fab")
		)
		(pad "1" smd rect
			(at 0.5334 0 180)
			(size 0.7112 0.6096)
			(layers "B.Cu" "B.Mask" "B.Paste")
			(net "UNNAMED_127_MT25QL128ABA1ESES_3")
		)
		(pad "2" smd rect
			(at -0.5334 0 180)
			(size 0.7112 0.6096)
			(layers "B.Cu" "B.Mask" "B.Paste")
			(net "FLASH_DQ2")
		)
		(zone
			(layer "B.Cu")
			(hatch none 0.5)
			(connect_pads
				(clearance 0)
			)
			(min_thickness 0.25)
			(keepout
				(tracks allowed)
				(vias not_allowed)
				(pads allowed)
				(copperpour not_allowed)
				(footprints allowed)
			)
			(placement
				(enabled no)
				(sheetname "")
			)
			(fill
				(thermal_gap 0.5)
				(thermal_bridge_width 0.5)
				(island_removal_mode 0)
			)
			(polygon
				(pts
					(xy 95.5548 -86.4362) (xy 95.7072 -86.4362) (xy 95.7072 -87.0458) (xy 95.5548 -87.0458)
				)
			)
		)
	)
)
